FILE_TYPE = CONNECTIVITY;
{Allegro Design Entry HDL 17.2-2016 S081 (4005846) 1/11/2022}
"PAGE_NUMBER" = 180;
0"NC";
1"GND\g";
2"GND\g";
3"GND\g";
4"GND\g";
%"UNIVERSAL_GND"
"1","(4500,-825)","0","logical_power","I10";
;
CDS_LIB"logical_power"
HDL_POWER"GND"
ROOM"IO_SLOT";
"A"4;
%"UNIVERSAL_GND"
"1","(-1200,-825)","0","logical_power","I2";
;
CDS_LIB"logical_power"
HDL_POWER"GND"
ROOM"IO_SLOT";
"A"3;
%"UNIVERSAL_GND"
"1","(2100,-825)","0","logical_power","I5";
;
CDS_LIB"logical_power"
HDL_POWER"GND"
ROOM"IO_SLOT";
"A"2;
%"EMMITSBURG_REV0P9"
"10","(-300,1450)","0","pure_quanta","I7";
;
PART_NUMBER"AJ0QV2N0T00"
PART_TYPE"SMLF"
VALUE"GFNOCPU04302300-QV2N-MM#99A1WT"
MATERIAL"IC"
$LOCATION"U4"
CDS_LIB"pure_quanta"
CDS_LMAN_SYM_OUTLINE"-500,1875,500,-1875"
NEEDS_NO_SIZE"TRUE"
CDS_LOCATION"U4"
$SEC"10"
CDS_SEC"10";
"VSS_E8"
$PN"E8"1;
"VSS_B39"
$PN"B39"1;
"VSS_C38"
$PN"C38"1;
"VSS_AY3"
$PN"AY3"1;
"VSS_BC36"
$PN"BC36"1;
"VSS_BD5"
$PN"BD5"1;
"VSS_E40"
$PN"E40"1;
"VSS_F41"
$PN"F41"3;
"VSS_AY39"
$PN"AY39"1;
"VSS_AY28"
$PN"AY28"1;
"VSS_AY31"
$PN"AY31"1;
"VSS_AY34"
$PN"AY34"1;
"VSS_AY37"
$PN"AY37"1;
"VSS_AY5"
$PN"AY5"1;
"VSS_AY8"
$PN"AY8"1;
"VSS_B13"
$PN"B13"1;
"VSS_B29"
$PN"B29"1;
"VSS_B9"
$PN"B9"1;
"VSS_BB39"
$PN"BB39"1;
"VSS_BB5"
$PN"BB5"1;
"VSS_BC10"
$PN"BC10"1;
"VSS_BC12"
$PN"BC12"1;
"VSS_BC14"
$PN"BC14"1;
"VSS_BC16"
$PN"BC16"1;
"VSS_BC18"
$PN"BC18"1;
"VSS_BC20"
$PN"BC20"1;
"VSS_BC22"
$PN"BC22"1;
"VSS_BC24"
$PN"BC24"1;
"VSS_BC26"
$PN"BC26"1;
"VSS_BC28"
$PN"BC28"1;
"VSS_BC30"
$PN"BC30"1;
"VSS_BC32"
$PN"BC32"1;
"VSS_BC34"
$PN"BC34"1;
"VSS_BC38"
$PN"BC38"1;
"VSS_BC6"
$PN"BC6"1;
"VSS_BC8"
$PN"BC8"1;
"VSS_BD21"
$PN"BD21"1;
"VSS_BD39"
$PN"BD39"1;
"VSS_BE10"
$PN"BE10"1;
"VSS_BE34"
$PN"BE34"1;
"VSS_BF21"
$PN"BF21"1;
"VSS_BG10"
$PN"BG10"1;
"VSS_BG34"
$PN"BG34"1;
"VSS_C20"
$PN"C20"1;
"VSS_C22"
$PN"C22"1;
"VSS_C24"
$PN"C24"1;
"VSS_C26"
$PN"C26"1;
"VSS_C4"
$PN"C4"1;
"VSS_D13"
$PN"D13"1;
"VSS_D29"
$PN"D29"1;
"VSS_D5"
$PN"D5"1;
"VSS_D9"
$PN"D9"1;
"VSS_E10"
$PN"E10"1;
"VSS_E12"
$PN"E12"1;
"VSS_E14"
$PN"E14"1;
"VSS_E16"
$PN"E16"1;
"VSS_E18"
$PN"E18"1;
"VSS_E20"
$PN"E20"1;
"VSS_E22"
$PN"E22"1;
"VSS_E24"
$PN"E24"1;
"VSS_E26"
$PN"E26"1;
"VSS_E28"
$PN"E28"1;
"VSS_E30"
$PN"E30"1;
"VSS_E32"
$PN"E32"1;
"VSS_E34"
$PN"E34"1;
"VSS_E36"
$PN"E36"1;
"VSS_E38"
$PN"E38"1;
"VSS_E6"
$PN"E6"1;
"VSS_F15"
$PN"F15"1;
"VSS_F24"
$PN"F24"1;
"VSS_F31"
$PN"F31"1;
"VSS_F34"
$PN"F34"3;
"VSS_F39"
$PN"F39"3;
"VSS_G13"
$PN"G13"3;
"VSS_G20"
$PN"G20"3;
"VSS_G26"
$PN"G26"3;
"VSS_H39"
$PN"H39"3;
"VSS_H5"
$PN"H5"3;
"VSS_H8"
$PN"H8"3;
"VSS_J13"
$PN"J13"3;
"VSS_J20"
$PN"J20"3;
"VSS_J26"
$PN"J26"3;
"VSS_K11"
$PN"K11"3;
"VSS_K15"
$PN"K15"3;
"VSS_K24"
$PN"K24"3;
"VSS_K34"
$PN"K34"3;
"VSS_K39"
$PN"K39"3;
"VSS_K5"
$PN"K5"3;
"VSS_L10"
$PN"L10"3;
"VSS_L16"
$PN"L16"3;
"VSS_L20"
$PN"L20"3;
"VSS_L23"
$PN"L23"3;
"VSS_L26"
$PN"L26"3;
"VSS_L29"
$PN"L29"3;
"VSS_L36"
$PN"L36"3;
"VSS_M1"
$PN"M1"3;
"VSS_M11"
$PN"M11"3;
"VSS_M15"
$PN"M15"3;
"VSS_M18"
$PN"M18"3;
"VSS_M21"
$PN"M21"3;
"VSS_M28"
$PN"M28"3;
"VSS_M3"
$PN"M3"3;
"VSS_M31"
$PN"M31"3;
"VSS_M34"
$PN"M34"3;
"VSS_M37"
$PN"M37"3;
"VSS_M39"
$PN"M39"3;
"VSS_M5"
$PN"M5"3;
"VSS_N16"
$PN"N16"3;
"VSS_N32"
$PN"N32"3;
"VSS_P11"
$PN"P11"3;
"VSS_P24"
$PN"P24"3;
"VSS_P28"
$PN"P28"3;
"VSS_P31"
$PN"P31"3;
"VSS_P37"
$PN"P37"3;
"VSS_P39"
$PN"P39"3;
"VSS_P41"
$PN"P41"3;
"VSS_P43"
$PN"P43"3;
"VSS_P5"
$PN"P5"3;
"VSS_P8"
$PN"P8"3;
"VSS_R13"
$PN"R13"3;
"VSS_R16"
$PN"R16"3;
"VSS_R20"
$PN"R20"3;
"VSS_R36"
$PN"R36"3;
"VSS_T31"
$PN"T31"3;
"VSS_U10"
$PN"U10"3;
"VSS_U13"
$PN"U13"3;
"VSS_U25"
$PN"U25"3;
"VSS_U39"
$PN"U39"3;
"VSS_U5"
$PN"U5"3;
"VSS_V2"
$PN"V2"3;
"VSS_V31"
$PN"V31"3;
"VSS_W25"
$PN"W25"3;
"VSS_W3"
$PN"W3"3;
"VSS_W39"
$PN"W39"3;
"VSS_W5"
$PN"W5"3;
"VSS_Y11"
$PN"Y11"3;
"VSS_Y15"
$PN"Y15"3;
"VSS_Y31"
$PN"Y31"3;
"VSS_Y34"
$PN"Y34"3;
"VSS_Y8"
$PN"Y8"3;
%"UNIVERSAL_GND"
"1","(600,-825)","0","logical_power","I8";
;
CDS_LIB"logical_power"
HDL_POWER"GND"
ROOM"IO_SLOT";
"A"1;
%"EMMITSBURG_REV0P9"
"11","(3300,1500)","0","pure_quanta","I9";
;
PART_NUMBER"AJ0QV2N0T00"
MATERIAL"IC"
VALUE"GFNOCPU04302300-QV2N-MM#99A1WT"
PART_TYPE"SMLF"
$LOCATION"U4"
CDS_LIB"pure_quanta"
CDS_LMAN_SYM_OUTLINE"-800,1825,800,-1825"
NEEDS_NO_SIZE"TRUE"
CDS_LOCATION"U4"
$SEC"11"
CDS_SEC"11";
"VSS_A20"
$PN"A20"4;
"VSS_A22"
$PN"A22"4;
"VSS_A24"
$PN"A24"4;
"VSS_A26"
$PN"A26"4;
"VSS_AA17"
$PN"AA17"4;
"VSS_AA19"
$PN"AA19"4;
"VSS_AA20"
$PN"AA20"4;
"VSS_AA22"
$PN"AA22"4;
"VSS_AA24"
$PN"AA24"4;
"VSS_AA25"
$PN"AA25"4;
"VSS_AA27"
$PN"AA27"4;
"VSS_AA32"
$PN"AA32"4;
"VSS_AA36"
$PN"AA36"4;
"VSS_AA39"
$PN"AA39"4;
"VSS_AA5"
$PN"AA5"4;
"VSS_AB15"
$PN"AB15"4;
"VSS_AB17"
$PN"AB17"4;
"VSS_AB25"
$PN"AB25"4;
"VSS_AB37"
$PN"AB37"4;
"VSS_AC29"
$PN"AC29"4;
"VSS_AC32"
$PN"AC32"4;
"VSS_AC36"
$PN"AC36"4;
"VSS_AC39"
$PN"AC39"4;
"VSS_AC5"
$PN"AC5"4;
"VSS_AD11"
$PN"AD11"4;
"VSS_AD19"
$PN"AD19"4;
"VSS_AD20"
$PN"AD20"4;
"VSS_AD22"
$PN"AD22"4;
"VSS_AD24"
$PN"AD24"4;
"VSS_AD31"
$PN"AD31"4;
"VSS_AD34"
$PN"AD34"4;
"VSS_AD8"
$PN"AD8"4;
"VSS_AE13"
$PN"AE13"4;
"VSS_AE39"
$PN"AE39"4;
"VSS_AE5"
$PN"AE5"4;
"VSS_AF19"
$PN"AF19"4;
"VSS_AF24"
$PN"AF24"4;
"VSS_AF31"
$PN"AF31"2;
"VSS_AF40"
$PN"AF40"2;
"VSS_AF42"
$PN"AF42"2;
"VSS_AG13"
$PN"AG13"2;
"VSS_AG19"
$PN"AG19"2;
"VSS_AG24"
$PN"AG24"2;
"VSS_AG39"
$PN"AG39"2;
"VSS_AG5"
$PN"AG5"2;
"VSS_AH31"
$PN"AH31"2;
"VSS_AH8"
$PN"AH8"2;
"VSS_AJ19"
$PN"AJ19"2;
"VSS_AJ24"
$PN"AJ24"2;
"VSS_AJ29"
$PN"AJ29"2;
"VSS_AJ36"
$PN"AJ36"2;
"VSS_AJ39"
$PN"AJ39"2;
"VSS_AJ5"
$PN"AJ5"2;
"VSS_AK11"
$PN"AK11"2;
"VSS_AK2"
$PN"AK2"2;
"VSS_AK37"
$PN"AK37"2;
"VSS_AK4"
$PN"AK4"2;
"VSS_AL19"
$PN"AL19"2;
"VSS_AL24"
$PN"AL24"2;
"VSS_AL27"
$PN"AL27"2;
"VSS_AL29"
$PN"AL29"2;
"VSS_AL39"
$PN"AL39"2;
"VSS_AM15"
$PN"AM15"2;
"VSS_AM31"
$PN"AM31"2;
"VSS_AM8"
$PN"AM8"2;
"VSS_AN13"
$PN"AN13"2;
"VSS_AN16"
$PN"AN16"2;
"VSS_AN29"
$PN"AN29"2;
"VSS_AN32"
$PN"AN32"2;
"VSS_AP11"
$PN"AP11"2;
"VSS_AP18"
$PN"AP18"2;
"VSS_AP24"
$PN"AP24"2;
"VSS_AP28"
$PN"AP28"2;
"VSS_AP37"
$PN"AP37"2;
"VSS_AP39"
$PN"AP39"2;
"VSS_AP5"
$PN"AP5"2;
"VSS_AR20"
$PN"AR20"2;
"VSS_AR32"
$PN"AR32"2;
"VSS_AT11"
$PN"AT11"2;
"VSS_AT15"
$PN"AT15"2;
"VSS_AT21"
$PN"AT21"2;
"VSS_AT24"
$PN"AT24"2;
"VSS_AT28"
$PN"AT28"2;
"VSS_AT31"
$PN"AT31"2;
"VSS_AT34"
$PN"AT34"2;
"VSS_AT39"
$PN"AT39"2;
"VSS_AT5"
$PN"AT5"2;
"VSS_AT8"
$PN"AT8"2;
"VSS_AU20"
$PN"AU20"2;
"VSS_AU23"
$PN"AU23"2;
"VSS_AU26"
$PN"AU26"2;
"VSS_AU29"
$PN"AU29"2;
"VSS_AU32"
$PN"AU32"2;
"VSS_AU36"
$PN"AU36"2;
"VSS_AV37"
$PN"AV37"2;
"VSS_AV39"
$PN"AV39"2;
"VSS_AV5"
$PN"AV5"2;
"VSS_AV8"
$PN"AV8"2;
"VSS_AW7"
$PN"AW7"2;
"VSS_AY11"
$PN"AY11"2;
"VSS_AY15"
$PN"AY15"2;
"VSS_AY18"
$PN"AY18"2;
"VSS_AY21"
$PN"AY21"2;
"VSS_AY24"
$PN"AY24"2;
"VSS_A38"
$PN"A38"4;
"VSS_A40"
$PN"A40"4;
"VSS_A6"
$PN"A6"4;
"VSS_BB1"
$PN"BB1"4;
"VSS_BG38"
$PN"BG38"4;
"VSS_BG4"
$PN"BG4"4;
"VSS_BG6"
$PN"BG6"4;
"VSS_F43"
$PN"F43"4;
"VSS_BC2"
$PN"BC2"4;
"VSS_BC42"
$PN"BC42"4;
"VSS_BD3"
$PN"BD3"4;
"VSS_BD41"
$PN"BD41"4;
"VSS_D3"
$PN"D3"4;
"VSS_D41"
$PN"D41"4;
"VSS_E2"
$PN"E2"4;
"VSS_E42"
$PN"E42"4;
"VSS_BD1"
$PN"BD1"4;
"VSS_BD43"
$PN"BD43"4;
"VSS_BE1"
$PN"BE1"4;
"VSS_BE3"
$PN"BE3"4;
"VSS_BE41"
$PN"BE41"4;
"VSS_BE43"
$PN"BE43"4;
"VSS_BG41"
$PN"BG41"4;
"VSS_C3"
$PN"C3"4;
"VSS_C41"
$PN"C41"4;
"VSS_C43"
$PN"C43"4;
"VSS_D1"
$PN"D1"4;
"VSS_D43"
$PN"D43"4;
END.
